(kicad_pcb
	(version 20241229)
	(generator "pcbnew")
	(generator_version "9.0")
	(general
		(thickness 1.62)
		(legacy_teardrops no)
	)
	(paper "A3")
	(title_block
		(title "COM Express 7 Baseboard")
		(date "2025-02-04")
		(rev "1.1.2")
		(company "Antmicro Ltd")
		(comment 1 "www.antmicro.com")
		(comment 9 "footprints 536-541 of 802")
	)
	(layers
		(0 "F.Cu" signal)
		(4 "In1.Cu" signal)
		(6 "In2.Cu" signal)
		(8 "In3.Cu" signal)
		(10 "In4.Cu" signal)
		(12 "In5.Cu" signal)
		(14 "In6.Cu" signal)
		(2 "B.Cu" signal)
		(9 "F.Adhes" user "F.Adhesive")
		(11 "B.Adhes" user "B.Adhesive")
		(13 "F.Paste" user)
		(15 "B.Paste" user)
		(5 "F.SilkS" user "F.Silkscreen")
		(7 "B.SilkS" user "B.Silkscreen")
		(1 "F.Mask" user)
		(3 "B.Mask" user)
		(17 "Dwgs.User" user "User.Drawings")
		(19 "Cmts.User" user "User.Comments")
		(21 "Eco1.User" user "User.Eco1")
		(23 "Eco2.User" user "User.Eco2")
		(25 "Edge.Cuts" user)
		(27 "Margin" user)
		(31 "F.CrtYd" user "F.Courtyard")
		(29 "B.CrtYd" user "B.Courtyard")
		(35 "F.Fab" user)
		(33 "B.Fab" user)
	)
	(footprint "antmicro-footprints:R_0402_1005Metric"
		(layer "B.Cu")
		(at 137.05 169.16 -90)
		(descr "Resistor SMD 0402")
		(tags "resistor SMD 0402")
		(property "Reference" "R60"
			(at -3.9 13.5 90)
			(layer "B.SilkS")
			(effects
				(font
					(size 0.7 0.7)
					(thickness 0.15)
				)
				(justify left bottom mirror)
			)
		)
		(property "Value" "R_0R_0402"
			(at -1.011843 -1.772047 90)
			(layer "B.Fab")
			(effects
				(font
					(size 0.7 0.7)
					(thickness 0.15)
				)
				(justify left bottom mirror)
			)
		)
		(property "Datasheet" "https://industrial.panasonic.com/cdbs/www-data/pdf/RDA0000/AOA0000C301.pdf"
			(at 0 0 270)
			(layer "F.Fab")
			(hide yes)
			(effects
				(font
					(size 1.27 1.27)
					(thickness 0.15)
				)
			)
		)
		(property "Author" "Antmicro"
			(at -32.11 306.21 0)
			(layer "B.Fab")
			(hide yes)
			(effects
				(font
					(size 1 1)
					(thickness 0.15)
				)
				(justify mirror)
			)
		)
		(property "Current" "1A"
			(at -32.11 306.21 0)
			(layer "B.Fab")
			(hide yes)
			(effects
				(font
					(size 1 1)
					(thickness 0.15)
				)
				(justify mirror)
			)
		)
		(property "License" "Apache-2.0"
			(at -32.11 306.21 0)
			(layer "B.Fab")
			(hide yes)
			(effects
				(font
					(size 1 1)
					(thickness 0.15)
				)
				(justify mirror)
			)
		)
		(property "MPN" "ERJ2GE0R00X"
			(at -32.11 306.21 0)
			(layer "B.Fab")
			(hide yes)
			(effects
				(font
					(size 1 1)
					(thickness 0.15)
				)
				(justify mirror)
			)
		)
		(property "Manufacturer" "Panasonic"
			(at -32.11 306.21 0)
			(layer "B.Fab")
			(hide yes)
			(effects
				(font
					(size 1 1)
					(thickness 0.15)
				)
				(justify mirror)
			)
		)
		(property "Public" "False"
			(at -32.11 306.21 0)
			(layer "B.Fab")
			(hide yes)
			(effects
				(font
					(size 1 1)
					(thickness 0.15)
				)
				(justify mirror)
			)
		)
		(property "Tolerance" ""
			(at -32.11 306.21 0)
			(layer "B.Fab")
			(hide yes)
			(effects
				(font
					(size 1 1)
					(thickness 0.15)
				)
				(justify mirror)
			)
		)
		(property "Val" "0R"
			(at -32.11 306.21 0)
			(layer "B.Fab")
			(hide yes)
			(effects
				(font
					(size 1 1)
					(thickness 0.15)
				)
				(justify mirror)
			)
		)
		(sheetname "2xSFP+")
		(sheetfile "2xSFP+.kicad_sch")
		(attr smd)
		(fp_rect
			(start -0.925 0.47)
			(end 0.925 -0.47)
			(stroke
				(width 0.05)
				(type default)
			)
			(fill no)
			(layer "B.CrtYd")
		)
		(fp_rect
			(start -0.5 0.25)
			(end 0.5 -0.25)
			(stroke
				(width 0.15)
				(type solid)
			)
			(fill no)
			(layer "B.Fab")
		)
		(pad "1" smd roundrect
			(at -0.48 0 270)
			(size 0.59 0.64)
			(layers "B.Cu" "B.Mask" "B.Paste")
			(roundrect_rratio 0.25)
			(net 897 "Net-(J2B-RS1)")
			(pintype "passive")
			(teardrops
				(best_length_ratio 0.2)
				(max_length 1)
				(best_width_ratio 0.9)
				(max_width 2)
				(curved_edges yes)
				(filter_ratio 0.9)
				(enabled yes)
				(allow_two_segments yes)
				(prefer_zone_connections yes)
			)
		)
		(pad "2" smd roundrect
			(at 0.48 0 270)
			(size 0.59 0.64)
			(layers "B.Cu" "B.Mask" "B.Paste")
			(roundrect_rratio 0.25)
			(net 1 "GND")
			(pintype "passive")
			(teardrops
				(best_length_ratio 0.2)
				(max_length 1)
				(best_width_ratio 0.9)
				(max_width 2)
				(curved_edges yes)
				(filter_ratio 0.9)
				(enabled yes)
				(allow_two_segments yes)
				(prefer_zone_connections yes)
			)
		)
	)
	(footprint "antmicro-footprints:R_0402_1005Metric"
		(layer "B.Cu")
		(at 123.4 111.81 180)
		(descr "Resistor SMD 0402")
		(tags "resistor SMD 0402")
		(property "Reference" "R5"
			(at -2.35 -0.45 0)
			(layer "B.SilkS")
			(effects
				(font
					(size 0.7 0.7)
					(thickness 0.15)
				)
				(justify left bottom mirror)
			)
		)
		(property "Value" "R_0R_0402"
			(at -1.011843 -1.772047 0)
			(layer "B.Fab")
			(effects
				(font
					(size 0.7 0.7)
					(thickness 0.15)
				)
				(justify left bottom mirror)
			)
		)
		(property "Datasheet" "https://industrial.panasonic.com/cdbs/www-data/pdf/RDA0000/AOA0000C301.pdf"
			(at 0 0 180)
			(layer "F.Fab")
			(hide yes)
			(effects
				(font
					(size 1.27 1.27)
					(thickness 0.15)
				)
			)
		)
		(property "Author" "Antmicro"
			(at 246.8 223.62 0)
			(layer "B.Fab")
			(hide yes)
			(effects
				(font
					(size 1 1)
					(thickness 0.15)
				)
				(justify mirror)
			)
		)
		(property "Current" "1A"
			(at 246.8 223.62 0)
			(layer "B.Fab")
			(hide yes)
			(effects
				(font
					(size 1 1)
					(thickness 0.15)
				)
				(justify mirror)
			)
		)
		(property "License" "Apache-2.0"
			(at 246.8 223.62 0)
			(layer "B.Fab")
			(hide yes)
			(effects
				(font
					(size 1 1)
					(thickness 0.15)
				)
				(justify mirror)
			)
		)
		(property "MPN" "ERJ2GE0R00X"
			(at 246.8 223.62 0)
			(layer "B.Fab")
			(hide yes)
			(effects
				(font
					(size 1 1)
					(thickness 0.15)
				)
				(justify mirror)
			)
		)
		(property "Manufacturer" "Panasonic"
			(at 246.8 223.62 0)
			(layer "B.Fab")
			(hide yes)
			(effects
				(font
					(size 1 1)
					(thickness 0.15)
				)
				(justify mirror)
			)
		)
		(property "Public" "False"
			(at 246.8 223.62 0)
			(layer "B.Fab")
			(hide yes)
			(effects
				(font
					(size 1 1)
					(thickness 0.15)
				)
				(justify mirror)
			)
		)
		(property "Tolerance" ""
			(at 246.8 223.62 0)
			(layer "B.Fab")
			(hide yes)
			(effects
				(font
					(size 1 1)
					(thickness 0.15)
				)
				(justify mirror)
			)
		)
		(property "Val" "0R"
			(at 246.8 223.62 0)
			(layer "B.Fab")
			(hide yes)
			(effects
				(font
					(size 1 1)
					(thickness 0.15)
				)
				(justify mirror)
			)
		)
		(sheetname "2xUSB3.0+RJ45")
		(sheetfile "usb3+rj45.kicad_sch")
		(attr smd)
		(fp_rect
			(start -0.925 0.47)
			(end 0.925 -0.47)
			(stroke
				(width 0.05)
				(type default)
			)
			(fill no)
			(layer "B.CrtYd")
		)
		(fp_rect
			(start -0.5 0.25)
			(end 0.5 -0.25)
			(stroke
				(width 0.15)
				(type solid)
			)
			(fill no)
			(layer "B.Fab")
		)
		(pad "1" smd roundrect
			(at -0.48 0 180)
			(size 0.59 0.64)
			(layers "B.Cu" "B.Mask" "B.Paste")
			(roundrect_rratio 0.25)
			(net 288 "/2xUSB3.0+RJ45/~{GBE0_LINK_1000}")
			(pintype "passive")
			(teardrops
				(best_length_ratio 0.2)
				(max_length 1)
				(best_width_ratio 0.9)
				(max_width 2)
				(curved_edges yes)
				(filter_ratio 0.9)
				(enabled yes)
				(allow_two_segments yes)
				(prefer_zone_connections yes)
			)
		)
		(pad "2" smd roundrect
			(at 0.48 0 180)
			(size 0.59 0.64)
			(layers "B.Cu" "B.Mask" "B.Paste")
			(roundrect_rratio 0.25)
			(net 157 "Net-(J1A-LED_D4)")
			(pintype "passive")
			(teardrops
				(best_length_ratio 0.2)
				(max_length 1)
				(best_width_ratio 0.9)
				(max_width 2)
				(curved_edges yes)
				(filter_ratio 0.9)
				(enabled yes)
				(allow_two_segments yes)
				(prefer_zone_connections yes)
			)
		)
	)
	(footprint "antmicro-footprints:C_0402_1005Metric"
		(layer "B.Cu")
		(at 136.79 133.86 180)
		(descr "Capacitor SMD 0402")
		(tags "capacitor SMD 0402")
		(property "Reference" "C185"
			(at -2.36 -2.65 135)
			(layer "B.SilkS")
			(effects
				(font
					(size 0.7 0.7)
					(thickness 0.15)
				)
				(justify left bottom mirror)
			)
		)
		(property "Value" "C_100n_0402"
			(at -1.022927 -2.155213 0)
			(layer "B.Fab")
			(effects
				(font
					(size 0.7 0.7)
					(thickness 0.15)
				)
				(justify left bottom mirror)
			)
		)
		(property "Datasheet" "https://www.murata.com/products/productdetail?partno=GRM155R61H104KE14%23"
			(at 0 0 180)
			(layer "F.Fab")
			(hide yes)
			(effects
				(font
					(size 1.27 1.27)
					(thickness 0.15)
				)
			)
		)
		(property "Author" "Antmicro"
			(at 273.58 267.72 0)
			(layer "B.Fab")
			(hide yes)
			(effects
				(font
					(size 1 1)
					(thickness 0.15)
				)
				(justify mirror)
			)
		)
		(property "Dielectric" "X5R"
			(at 273.58 267.72 0)
			(layer "B.Fab")
			(hide yes)
			(effects
				(font
					(size 1 1)
					(thickness 0.15)
				)
				(justify mirror)
			)
		)
		(property "License" "Apache-2.0"
			(at 273.58 267.72 0)
			(layer "B.Fab")
			(hide yes)
			(effects
				(font
					(size 1 1)
					(thickness 0.15)
				)
				(justify mirror)
			)
		)
		(property "MPN" "GRM155R61H104KE14D"
			(at 273.58 267.72 0)
			(layer "B.Fab")
			(hide yes)
			(effects
				(font
					(size 1 1)
					(thickness 0.15)
				)
				(justify mirror)
			)
		)
		(property "Manufacturer" "Murata"
			(at 273.58 267.72 0)
			(layer "B.Fab")
			(hide yes)
			(effects
				(font
					(size 1 1)
					(thickness 0.15)
				)
				(justify mirror)
			)
		)
		(property "Public" "False"
			(at 273.58 267.72 0)
			(layer "B.Fab")
			(hide yes)
			(effects
				(font
					(size 1 1)
					(thickness 0.15)
				)
				(justify mirror)
			)
		)
		(property "Val" "100n"
			(at 273.58 267.72 0)
			(layer "B.Fab")
			(hide yes)
			(effects
				(font
					(size 1 1)
					(thickness 0.15)
				)
				(justify mirror)
			)
		)
		(property "Voltage" "50V"
			(at 273.58 267.72 0)
			(layer "B.Fab")
			(hide yes)
			(effects
				(font
					(size 1 1)
					(thickness 0.15)
				)
				(justify mirror)
			)
		)
		(sheetname "KR to SFI #2")
		(sheetfile "kr_sfi.kicad_sch")
		(attr smd)
		(fp_rect
			(start -0.925 0.47)
			(end 0.925 -0.47)
			(stroke
				(width 0.05)
				(type default)
			)
			(fill no)
			(layer "B.CrtYd")
		)
		(fp_line
			(start 0.504 0.25)
			(end -0.494 0.25)
			(stroke
				(width 0.15)
				(type solid)
			)
			(layer "B.Fab")
		)
		(fp_line
			(start 0.504 -0.248)
			(end 0.504 0.25)
			(stroke
				(width 0.15)
				(type solid)
			)
			(layer "B.Fab")
		)
		(fp_line
			(start -0.494 0.25)
			(end -0.494 -0.248)
			(stroke
				(width 0.15)
				(type solid)
			)
			(layer "B.Fab")
		)
		(fp_line
			(start -0.494 -0.248)
			(end 0.504 -0.248)
			(stroke
				(width 0.15)
				(type solid)
			)
			(layer "B.Fab")
		)
		(pad "1" smd roundrect
			(at -0.48 0 180)
			(size 0.59 0.64)
			(layers "B.Cu" "B.Mask" "B.Paste")
			(roundrect_rratio 0.25)
			(net 1 "GND")
			(pintype "passive")
			(teardrops
				(best_length_ratio 0.2)
				(max_length 1)
				(best_width_ratio 0.9)
				(max_width 2)
				(curved_edges yes)
				(filter_ratio 0.9)
				(enabled yes)
				(allow_two_segments yes)
				(prefer_zone_connections yes)
			)
		)
		(pad "2" smd roundrect
			(at 0.48 0 180)
			(size 0.59 0.64)
			(layers "B.Cu" "B.Mask" "B.Paste")
			(roundrect_rratio 0.25)
			(net 78 "+1V8")
			(pintype "passive")
			(teardrops
				(best_length_ratio 0.2)
				(max_length 1)
				(best_width_ratio 0.9)
				(max_width 2)
				(curved_edges yes)
				(filter_ratio 0.9)
				(enabled yes)
				(allow_two_segments yes)
				(prefer_zone_connections yes)
			)
		)
	)
	(footprint "antmicro-footprints:R_0402_1005Metric"
		(layer "B.Cu")
		(at 308.824999 121.96 -90)
		(descr "Resistor SMD 0402")
		(tags "resistor SMD 0402")
		(property "Reference" "R89"
			(at 0.8 -0.475001 90)
			(layer "B.SilkS")
			(effects
				(font
					(size 0.7 0.7)
					(thickness 0.15)
				)
				(justify left bottom mirror)
			)
		)
		(property "Value" "R_10k_0402"
			(at -1.011843 -1.772047 90)
			(layer "B.Fab")
			(effects
				(font
					(size 0.7 0.7)
					(thickness 0.15)
				)
				(justify left bottom mirror)
			)
		)
		(property "Datasheet" "https://www.bourns.com/docs/product-datasheets/cr.pdf"
			(at 0 0 270)
			(layer "F.Fab")
			(hide yes)
			(effects
				(font
					(size 1.27 1.27)
					(thickness 0.15)
				)
			)
		)
		(property "Author" "Antmicro"
			(at 186.864999 430.784999 0)
			(layer "B.Fab")
			(hide yes)
			(effects
				(font
					(size 1 1)
					(thickness 0.15)
				)
				(justify mirror)
			)
		)
		(property "License" "Apache-2.0"
			(at 186.864999 430.784999 0)
			(layer "B.Fab")
			(hide yes)
			(effects
				(font
					(size 1 1)
					(thickness 0.15)
				)
				(justify mirror)
			)
		)
		(property "MPN" "CR0402-FX-1002GLF"
			(at 186.864999 430.784999 0)
			(layer "B.Fab")
			(hide yes)
			(effects
				(font
					(size 1 1)
					(thickness 0.15)
				)
				(justify mirror)
			)
		)
		(property "Manufacturer" "Bourns"
			(at 186.864999 430.784999 0)
			(layer "B.Fab")
			(hide yes)
			(effects
				(font
					(size 1 1)
					(thickness 0.15)
				)
				(justify mirror)
			)
		)
		(property "Public" "False"
			(at 186.864999 430.784999 0)
			(layer "B.Fab")
			(hide yes)
			(effects
				(font
					(size 1 1)
					(thickness 0.15)
				)
				(justify mirror)
			)
		)
		(property "Tolerance" "1%"
			(at 186.864999 430.784999 0)
			(layer "B.Fab")
			(hide yes)
			(effects
				(font
					(size 1 1)
					(thickness 0.15)
				)
				(justify mirror)
			)
		)
		(property "Val" "10k"
			(at 186.864999 430.784999 0)
			(layer "B.Fab")
			(hide yes)
			(effects
				(font
					(size 1 1)
					(thickness 0.15)
				)
				(justify mirror)
			)
		)
		(sheetname "Power")
		(sheetfile "power.kicad_sch")
		(attr smd)
		(fp_rect
			(start -0.925 0.47)
			(end 0.925 -0.47)
			(stroke
				(width 0.05)
				(type default)
			)
			(fill no)
			(layer "B.CrtYd")
		)
		(fp_rect
			(start -0.5 0.25)
			(end 0.5 -0.25)
			(stroke
				(width 0.15)
				(type solid)
			)
			(fill no)
			(layer "B.Fab")
		)
		(pad "1" smd roundrect
			(at -0.48 0 270)
			(size 0.59 0.64)
			(layers "B.Cu" "B.Mask" "B.Paste")
			(roundrect_rratio 0.25)
			(net 1 "GND")
			(pintype "passive")
			(teardrops
				(best_length_ratio 0.2)
				(max_length 1)
				(best_width_ratio 0.9)
				(max_width 2)
				(curved_edges yes)
				(filter_ratio 0.9)
				(enabled yes)
				(allow_two_segments yes)
				(prefer_zone_connections yes)
			)
		)
		(pad "2" smd roundrect
			(at 0.48 0 270)
			(size 0.59 0.64)
			(layers "B.Cu" "B.Mask" "B.Paste")
			(roundrect_rratio 0.25)
			(net 575 "Net-(U18-MODE)")
			(pintype "passive")
			(teardrops
				(best_length_ratio 0.2)
				(max_length 1)
				(best_width_ratio 0.9)
				(max_width 2)
				(curved_edges yes)
				(filter_ratio 0.9)
				(enabled yes)
				(allow_two_segments yes)
				(prefer_zone_connections yes)
			)
		)
	)
	(footprint "antmicro-footprints:C_0402_1005Metric"
		(layer "B.Cu")
		(at 134.79 132.86)
		(descr "Capacitor SMD 0402")
		(tags "capacitor SMD 0402")
		(property "Reference" "C200"
			(at -1.84 1.35 0)
			(layer "B.SilkS")
			(effects
				(font
					(size 0.7 0.7)
					(thickness 0.15)
				)
				(justify right bottom mirror)
			)
		)
		(property "Value" "C_100n_0402"
			(at -1.022927 -2.155213 0)
			(layer "B.Fab")
			(effects
				(font
					(size 0.7 0.7)
					(thickness 0.15)
				)
				(justify right bottom mirror)
			)
		)
		(property "Datasheet" "https://www.murata.com/products/productdetail?partno=GRM155R61H104KE14%23"
			(at 0 0 0)
			(layer "F.Fab")
			(hide yes)
			(effects
				(font
					(size 1.27 1.27)
					(thickness 0.15)
				)
			)
		)
		(property "Author" "Antmicro"
			(at 0 0 0)
			(layer "B.Fab")
			(hide yes)
			(effects
				(font
					(size 1 1)
					(thickness 0.15)
				)
				(justify mirror)
			)
		)
		(property "Dielectric" "X5R"
			(at 0 0 0)
			(layer "B.Fab")
			(hide yes)
			(effects
				(font
					(size 1 1)
					(thickness 0.15)
				)
				(justify mirror)
			)
		)
		(property "License" "Apache-2.0"
			(at 0 0 0)
			(layer "B.Fab")
			(hide yes)
			(effects
				(font
					(size 1 1)
					(thickness 0.15)
				)
				(justify mirror)
			)
		)
		(property "MPN" "GRM155R61H104KE14D"
			(at 0 0 0)
			(layer "B.Fab")
			(hide yes)
			(effects
				(font
					(size 1 1)
					(thickness 0.15)
				)
				(justify mirror)
			)
		)
		(property "Manufacturer" "Murata"
			(at 0 0 0)
			(layer "B.Fab")
			(hide yes)
			(effects
				(font
					(size 1 1)
					(thickness 0.15)
				)
				(justify mirror)
			)
		)
		(property "Public" "False"
			(at 0 0 0)
			(layer "B.Fab")
			(hide yes)
			(effects
				(font
					(size 1 1)
					(thickness 0.15)
				)
				(justify mirror)
			)
		)
		(property "Val" "100n"
			(at 0 0 0)
			(layer "B.Fab")
			(hide yes)
			(effects
				(font
					(size 1 1)
					(thickness 0.15)
				)
				(justify mirror)
			)
		)
		(property "Voltage" "50V"
			(at 0 0 0)
			(layer "B.Fab")
			(hide yes)
			(effects
				(font
					(size 1 1)
					(thickness 0.15)
				)
				(justify mirror)
			)
		)
		(sheetname "KR to SFI #2")
		(sheetfile "kr_sfi.kicad_sch")
		(attr smd)
		(fp_rect
			(start -0.925 0.47)
			(end 0.925 -0.47)
			(stroke
				(width 0.05)
				(type default)
			)
			(fill no)
			(layer "B.CrtYd")
		)
		(fp_line
			(start -0.494 -0.248)
			(end 0.504 -0.248)
			(stroke
				(width 0.15)
				(type solid)
			)
			(layer "B.Fab")
		)
		(fp_line
			(start -0.494 0.25)
			(end -0.494 -0.248)
			(stroke
				(width 0.15)
				(type solid)
			)
			(layer "B.Fab")
		)
		(fp_line
			(start 0.504 -0.248)
			(end 0.504 0.25)
			(stroke
				(width 0.15)
				(type solid)
			)
			(layer "B.Fab")
		)
		(fp_line
			(start 0.504 0.25)
			(end -0.494 0.25)
			(stroke
				(width 0.15)
				(type solid)
			)
			(layer "B.Fab")
		)
		(pad "1" smd roundrect
			(at -0.48 0)
			(size 0.59 0.64)
			(layers "B.Cu" "B.Mask" "B.Paste")
			(roundrect_rratio 0.25)
			(net 1 "GND")
			(pintype "passive")
			(teardrops
				(best_length_ratio 0.2)
				(max_length 1)
				(best_width_ratio 0.9)
				(max_width 2)
				(curved_edges yes)
				(filter_ratio 0.9)
				(enabled yes)
				(allow_two_segments yes)
				(prefer_zone_connections yes)
			)
		)
		(pad "2" smd roundrect
			(at 0.48 0)
			(size 0.59 0.64)
			(layers "B.Cu" "B.Mask" "B.Paste")
			(roundrect_rratio 0.25)
			(net 74 "+1V0")
			(pintype "passive")
			(teardrops
				(best_length_ratio 0.2)
				(max_length 1)
				(best_width_ratio 0.9)
				(max_width 2)
				(curved_edges yes)
				(filter_ratio 0.9)
				(enabled yes)
				(allow_two_segments yes)
				(prefer_zone_connections yes)
			)
		)
	)
	(footprint "antmicro-footprints:TP_SMD_0.75mm"
		(layer "B.Cu")
		(at 175.15 163.8 180)
		(property "Reference" "TP28"
			(at -0.35 3.3 90)
			(layer "B.SilkS")
			(effects
				(font
					(size 0.7 0.7)
					(thickness 0.15)
				)
				(justify left bottom mirror)
			)
		)
		(property "Value" "TP_0.75mm_SMD"
			(at 3.225 -53.865 0)
			(layer "B.Fab")
			(hide yes)
			(effects
				(font
					(size 0.7 0.7)
					(thickness 0.15)
				)
				(justify left bottom mirror)
			)
		)
		(property "Author" "Antmicro"
			(at 459.7 308.02 0)
			(layer "B.Fab")
			(hide yes)
			(effects
				(font
					(size 1 1)
					(thickness 0.15)
				)
				(justify mirror)
			)
		)
		(property "License" "Apache-2.0"
			(at 459.7 308.02 0)
			(layer "B.Fab")
			(hide yes)
			(effects
				(font
					(size 1 1)
					(thickness 0.15)
				)
				(justify mirror)
			)
		)
		(property "MPN" ""
			(at 459.7 308.02 0)
			(layer "B.Fab")
			(hide yes)
			(effects
				(font
					(size 1 1)
					(thickness 0.15)
				)
				(justify mirror)
			)
		)
		(property "Manufacturer" ""
			(at 459.7 308.02 0)
			(layer "B.Fab")
			(hide yes)
			(effects
				(font
					(size 1 1)
					(thickness 0.15)
				)
				(justify mirror)
			)
		)
		(property "Public" "False"
			(at 459.7 308.02 0)
			(layer "B.Fab")
			(hide yes)
			(effects
				(font
					(size 1 1)
					(thickness 0.15)
				)
				(justify mirror)
			)
		)
		(sheetname "Com Express 7 MGMT")
		(sheetfile "com_express_7_mgmt.kicad_sch")
		(attr exclude_from_pos_files exclude_from_bom)
		(fp_circle
			(center 0 0)
			(end 0.475 0)
			(stroke
				(width 0.05)
				(type default)
			)
			(fill no)
			(layer "B.CrtYd")
		)
		(pad "1" smd circle
			(at 0 0 180)
			(size 0.75 0.75)
			(layers "B.Cu" "B.Mask")
			(net 348 "Net-(J12D-~{LPC_FRAME}{slash}~{ESPI_CS0})")
			(pinfunction "1")
			(pintype "passive")
			(teardrops
				(best_length_ratio 0.4)
				(max_length 1)
				(best_width_ratio 0.9)
				(max_width 2)
				(curved_edges yes)
				(filter_ratio 0.9)
				(enabled yes)
				(allow_two_segments yes)
				(prefer_zone_connections yes)
			)
		)
	)
)
